# BASEBOARD_FAB2 (Tioga Pass) — schematic netlist excerpt (pin names and nets, part order shuffled) for the footprints in the layout excerpt that follows; sources: Cadence DE-HDL packaged netlist, KiCad conversion of Wiwynn_Tioga_Pass_MB.brd

J9T1  SCONN288_H44441003  SCONN  pkg PIP  page 78
  \12v\(1)  = P12V_NVDIMM_GHJ
  VSS(93)  = GND
  DQ(4)  = M_G_DQ<4>
  VSS(92)  = GND
  DQ(0)  = M_G_DQ<0>
  VSS(91)  = GND
  DQS9P  = M_G_DQS_DP<9>
  DQS9N  = M_G_DQS_DN<9>
  VSS(90)  = GND
  DQ(6)  = M_G_DQ<6>
  VSS(89)  = GND
  DQ(2)  = M_G_DQ<2>
  VSS(88)  = GND
  DQ(12)  = M_G_DQ<12>
  VSS(87)  = GND
  DQ(8)  = M_G_DQ<8>
  VSS(86)  = GND
  DQS10P  = M_G_DQS_DP<10>
  DQS10N  = M_G_DQS_DN<10>
  VSS(85)  = GND
  DQ(14)  = M_G_DQ<14>
  VSS(84)  = GND
  DQ(10)  = M_G_DQ<10>
  VSS(83)  = GND
  DQ(20)  = M_G_DQ<20>
  VSS(82)  = GND
  DQ(16)  = M_G_DQ<16>
  VSS(81)  = GND
  DQS11P  = M_G_DQS_DP<11>
  DQS11N  = M_G_DQS_DN<11>
  VSS(80)  = GND
  DQ(22)  = M_G_DQ<22>
  VSS(79)  = GND
  DQ(18)  = M_G_DQ<18>
  VSS(78)  = GND
  DQ(28)  = M_G_DQ<28>
  VSS(77)  = GND
  DQ(24)  = M_G_DQ<24>
  VSS(76)  = GND
  DQS12P  = M_G_DQS_DP<12>
  DQS12N  = M_G_DQS_DN<12>
  VSS(75)  = GND
  DQ(30)  = M_G_DQ<30>
  VSS(74)  = GND
  DQ(26)  = M_G_DQ<26>
  VSS(73)  = GND
  CB(4)  = M_G_ECC<4>
  VSS(72)  = GND
  CB(0)  = M_G_ECC<0>
  VSS(71)  = GND
  DQS17P  = M_G_DQS_DP<17>
  DQS17N  = M_G_DQS_DN<17>
  VSS(70)  = GND
  CB(6)  = M_G_ECC<6>
  VSS(69)  = GND
  CB(2)  = M_G_ECC<2>
  VSS(68)  = GND
  RESET_N  = M_GHJ_RST_N
  VDD(25)  = PVDDQ_GHJ
  CKE(0)  = M_G_CKE<2>
  VDD(24)  = PVDDQ_GHJ
  ACT_N  = M_G_ACT_N
  BG(0)  = M_G_BG<0>
  VDD(23)  = PVDDQ_GHJ
  A12  = M_G_MA<12>
  A9  = M_G_MA<9>
  VDD(22)  = PVDDQ_GHJ
  A8  = M_G_MA<8>
  A6  = M_G_MA<6>
  VDD(21)  = PVDDQ_GHJ
  A3  = M_G_MA<3>
  A1  = M_G_MA<1>
  VDD(20)  = PVDDQ_GHJ
  CK0P  = M_G_CLK_DP<2>
  CK0N  = M_G_CLK_DN<2>
  VDD(19)  = PVDDQ_GHJ
  VTT(1)  = PVTT_GHJ
  EVENT_N  = FM_DIMM_EVENT_COD_N
  A0  = M_G_MA<0>
  VDD(18)  = PVDDQ_GHJ
  BA(0)  = M_G_BA<0>
  A16_RAS_N  = M_G_MA<16>
  VDD(17)  = PVDDQ_GHJ
  S0_N  = M_G_CS_N<4>
  VDD(16)  = PVDDQ_GHJ
  A15_CAS_N  = M_G_MA<15>
  ODT(0)  = M_G_ODT<2>
  VDD(15)  = PVDDQ_GHJ
  S1_N  = M_G_CS_N<5>
  VDD(14)  = PVDDQ_GHJ
  ODT(1)  = M_G_ODT<3>
  VDD(13)  = PVDDQ_GHJ
  S2_N_C(0)  = M_G_CS_N<6>
  VSS(67)  = GND
  DQ(36)  = M_G_DQ<36>
  VSS(66)  = GND
  DQ(32)  = M_G_DQ<32>
  VSS(65)  = GND
  DQS13P  = M_G_DQS_DP<13>
  DQS13N  = M_G_DQS_DN<13>
  VSS(64)  = GND
  DQ(38)  = M_G_DQ<38>
  VSS(63)  = GND
  DQ(34)  = M_G_DQ<34>
  VSS(62)  = GND
  DQ(44)  = M_G_DQ<44>
  VSS(61)  = GND
  DQ(40)  = M_G_DQ<40>
  VSS(60)  = GND
  DQS14P  = M_G_DQS_DP<14>
  DQS14N  = M_G_DQS_DN<14>
  VSS(59)  = GND
  DQ(46)  = M_G_DQ<46>
  VSS(58)  = GND
  DQ(42)  = M_G_DQ<42>
  VSS(57)  = GND
  DQ(52)  = M_G_DQ<52>
  VSS(56)  = GND
  DQ(48)  = M_G_DQ<48>
  VSS(55)  = GND
  DQS15P  = M_G_DQS_DP<15>
  DQS15N  = M_G_DQS_DN<15>
  VSS(54)  = GND
  DQ(54)  = M_G_DQ<54>
  VSS(53)  = GND
  DQ(50)  = M_G_DQ<50>
  VSS(52)  = GND
  DQ(60)  = M_G_DQ<60>
  VSS(51)  = GND
  DQ(56)  = M_G_DQ<56>
  VSS(50)  = GND
  DQS16P  = M_G_DQS_DP<16>
  DQS16N  = M_G_DQS_DN<16>
  VSS(49)  = GND
  DQ(62)  = M_G_DQ<62>
  VSS(48)  = GND
  DQ(58)  = M_G_DQ<58>
  VSS(47)  = GND
  SA(0)  = PVPP_GHJ
  SA(1)  = GND
  SCL  = SMB_DDR_GHJ_VPP_SCL
  VPP(4)  = PVPP_GHJ
  VPP(3)  = PVPP_GHJ
  RFU(2)  = TP_CH_G_DIMM0_RFU_2
  \12v\(0)  = P12V_NVDIMM_GHJ
  VREFCA  = M_G_VREF
  VSS(46)  = GND
  DQ(5)  = M_G_DQ<5>
  VSS(45)  = GND
  DQ(1)  = M_G_DQ<1>
  VSS(44)  = GND
  DQS0N  = M_G_DQS_DN<0>
  DQS0P  = M_G_DQS_DP<0>
  VSS(43)  = GND
  DQ(7)  = M_G_DQ<7>
  VSS(42)  = GND
  DQ(3)  = M_G_DQ<3>
  VSS(41)  = GND
  DQ(13)  = M_G_DQ<13>
  VSS(40)  = GND
  DQ(9)  = M_G_DQ<9>
  VSS(39)  = GND
  DQS1N  = M_G_DQS_DN<1>
  DQS1P  = M_G_DQS_DP<1>
  VSS(38)  = GND
  DQ(15)  = M_G_DQ<15>
  VSS(37)  = GND
  DQ(11)  = M_G_DQ<11>
  VSS(36)  = GND
  DQ(21)  = M_G_DQ<21>
  VSS(35)  = GND
  DQ(17)  = M_G_DQ<17>
  VSS(34)  = GND
  DQS2N  = M_G_DQS_DN<2>
  DQS2P  = M_G_DQS_DP<2>
  VSS(33)  = GND
  DQ(23)  = M_G_DQ<23>
  VSS(32)  = GND
  DQ(19)  = M_G_DQ<19>
  VSS(31)  = GND
  DQ(29)  = M_G_DQ<29>
  VSS(30)  = GND
  DQ(25)  = M_G_DQ<25>
  VSS(29)  = GND
  DQS3N  = M_G_DQS_DN<3>
  DQS3P  = M_G_DQS_DP<3>
  VSS(28)  = GND
  DQ(31)  = M_G_DQ<31>
  VSS(27)  = GND
  DQ(27)  = M_G_DQ<27>
  VSS(26)  = GND
  CB(5)  = M_G_ECC<5>
  VSS(25)  = GND
  CB(1)  = M_G_ECC<1>
  VSS(24)  = GND
  DQS8N  = M_G_DQS_DN<8>
  DQS8P  = M_G_DQS_DP<8>
  VSS(23)  = GND
  CB(7)  = M_G_ECC<7>
  VSS(22)  = GND
  CB(3)  = M_G_ECC<3>
  VSS(21)  = GND
  CKE(1)  = M_G_CKE<3>
  VDD(12)  = PVDDQ_GHJ
  RFU(0)  = TP_CH_G_DIMM0_RFU_0
  VDD(11)  = PVDDQ_GHJ
  BG(1)  = M_G_BG<1>
  ALERT_N  = M_G_ALERT_N
  VDD(10)  = PVDDQ_GHJ
  A11  = M_G_MA<11>
  A7  = M_G_MA<7>
  VDD(9)  = PVDDQ_GHJ
  A5  = M_G_MA<5>
  A4  = M_G_MA<4>
  VDD(8)  = PVDDQ_GHJ
  A2  = M_G_MA<2>
  VDD(7)  = PVDDQ_GHJ
  CK1P  = M_G_CLK_DP<3>
  CK1N  = M_G_CLK_DN<3>
  VDD(6)  = PVDDQ_GHJ
  VTT(0)  = PVTT_GHJ
  PAR  = M_G_PAR
  VDD(5)  = PVDDQ_GHJ
  BA(1)  = M_G_BA<1>
  A10  = M_G_MA<10>
  VDD(4)  = PVDDQ_GHJ
  RFU(1)  = TP_CH_G_DIMM0_RFU_1
  A14_WE_N  = M_G_MA<14>
  VDD(3)  = PVDDQ_GHJ
  SAVE_N_NC  = FM_ADR_COMPLETE_GHJ_N
  VDD(2)  = PVDDQ_GHJ
  A13  = M_G_MA<13>
  VDD(1)  = PVDDQ_GHJ
  A17  = M_G_MA<17>
  C(2)  = M_G_C<2>
  VDD(0)  = PVDDQ_GHJ
  S3_N_C(1)  = M_G_CS_N<7>
  SA(2)  = GND
  VSS(20)  = GND
  DQ(37)  = M_G_DQ<37>
  VSS(19)  = GND
  DQ(33)  = M_G_DQ<33>
  VSS(18)  = GND
  DQS4N  = M_G_DQS_DN<4>
  DQS4P  = M_G_DQS_DP<4>
  VSS(17)  = GND
  DQ(39)  = M_G_DQ<39>
  VSS(16)  = GND
  DQ(35)  = M_G_DQ<35>
  VSS(15)  = GND
  DQ(45)  = M_G_DQ<45>
  VSS(14)  = GND
  DQ(41)  = M_G_DQ<41>
  VSS(13)  = GND
  DQS5N  = M_G_DQS_DN<5>
  DQS5P  = M_G_DQS_DP<5>
  VSS(12)  = GND
  DQ(47)  = M_G_DQ<47>
  VSS(11)  = GND
  DQ(43)  = M_G_DQ<43>
  VSS(10)  = GND
  DQ(53)  = M_G_DQ<53>
  VSS(9)  = GND
  DQ(49)  = M_G_DQ<49>
  VSS(8)  = GND
  DQS6N  = M_G_DQS_DN<6>
  DQS6P  = M_G_DQS_DP<6>
  VSS(7)  = GND
  DQ(55)  = M_G_DQ<55>
  VSS(6)  = GND
  DQ(51)  = M_G_DQ<51>
  VSS(5)  = GND
  DQ(61)  = M_G_DQ<61>
  VSS(4)  = GND
  DQ(57)  = M_G_DQ<57>
  VSS(3)  = GND
  DQS7N  = M_G_DQS_DN<7>
  DQS7P  = M_G_DQS_DP<7>
  VSS(2)  = GND
  DQ(63)  = M_G_DQ<63>
  VSS(1)  = GND
  DQ(59)  = M_G_DQ<59>
  VSS(0)  = GND
  VDDSPD  = PVPP_GHJ
  SDA  = SMB_DDR_GHJ_VPP_SDA
  VPP(1)  = PVPP_GHJ
  VPP(0)  = PVPP_GHJ
  VPP(2)  = PVPP_GHJ

(kicad_pcb
	(version 20260206)
	(generator "pcbnew")
	(generator_version "10.0")
	(general
		(thickness 1.6)
		(legacy_teardrops no)
	)
	(paper "A4")
	(title_block
		(title "Wiwynn_Tioga_Pass_MB.brd")
		(comment 1 "Tioga Pass / footprint 4084 of 4770 (J9T1), pads 51-100 of 291")
	)
	(layers
		(0 "F.Cu" signal "TOP")
		(4 "In1.Cu" signal "L2GND")
		(6 "In2.Cu" signal "L3")
		(8 "In3.Cu" signal "L4GND")
		(10 "In4.Cu" signal "L5")
		(12 "In5.Cu" signal "L6GND")
		(14 "In6.Cu" signal "L7VCC")
		(16 "In7.Cu" signal "L8VCC")
		(18 "In8.Cu" signal "L9GND")
		(20 "In9.Cu" signal "L10")
		(22 "In10.Cu" signal "L11GND")
		(24 "In11.Cu" signal "L12")
		(26 "In12.Cu" signal "L13GND")
		(2 "B.Cu" signal "BOTTOM")
		(9 "F.Adhes" user "F.Adhesive")
		(11 "B.Adhes" user "B.Adhesive")
		(13 "F.Paste" user "Package Geometry/Pastemask Top")
		(15 "B.Paste" user "Package Geometry/Pastemask Bottom")
		(5 "F.SilkS" user "Ref Des/Silkscreen Top")
		(7 "B.SilkS" user "Ref Des/Silkscreen Bottom")
		(1 "F.Mask" user "Board Geometry/Soldermask Top")
		(3 "B.Mask" user "Board Geometry/Soldermask Bottom")
		(17 "Dwgs.User" user "User.Drawings")
		(19 "Cmts.User" user "User.Comments")
		(21 "Eco1.User" user "User.Eco1")
		(23 "Eco2.User" user "User.Eco2")
		(25 "Edge.Cuts" user "Board Geometry/Outline")
		(27 "Margin" user)
		(31 "F.CrtYd" user "Package Geometry/Place Bound Top")
		(29 "B.CrtYd" user "Package Geometry/Place Bound Bottom")
		(35 "F.Fab" user "Ref Des/Assembly Top")
		(33 "B.Fab" user "Ref Des/Assembly Bottom")
	)
	(footprint ""
		(layer "B.Cu")
		(at 29.699458 -24.824182 90)
		(property "Reference" "J9T1"
			(at 2.200148 39.261542 0)
			(unlocked yes)
			(layer "B.SilkS")
			(effects
				(font
					(size 0.7874 0.5842)
					(thickness 0.1524)
				)
				(justify left mirror)
			)
		)
		(property "Value" ""
			(at 0 0 90)
			(layer "B.Fab")
			(effects
				(font
					(size 1.27 1.27)
				)
				(justify mirror)
			)
		)
		(duplicate_pad_numbers_are_jumpers no)
		(pad "48" smd rect
			(at 0 39.949882 270)
			(size 1.8034 0.508)
			(layers "B.Cu" "B.Mask" "B.Paste")
			(net "GND")
		)
		(pad "49" smd rect
			(at 0 40.80002 270)
			(size 1.8034 0.508)
			(layers "B.Cu" "B.Mask" "B.Paste")
			(net "M_G_ECC<0>")
		)
		(pad "50" smd rect
			(at 0 41.649904 270)
			(size 1.8034 0.508)
			(layers "B.Cu" "B.Mask" "B.Paste")
			(net "GND")
		)
		(pad "51" smd rect
			(at 0 42.500042 270)
			(size 1.8034 0.508)
			(layers "B.Cu" "B.Mask" "B.Paste")
			(net "M_G_DQS_DP<17>")
		)
		(pad "52" smd rect
			(at 0 43.349926 270)
			(size 1.8034 0.508)
			(layers "B.Cu" "B.Mask" "B.Paste")
			(net "M_G_DQS_DN<17>")
		)
		(pad "53" smd rect
			(at 0 44.200064 270)
			(size 1.8034 0.508)
			(layers "B.Cu" "B.Mask" "B.Paste")
			(net "GND")
		)
		(pad "54" smd rect
			(at 0 45.049948 270)
			(size 1.8034 0.508)
			(layers "B.Cu" "B.Mask" "B.Paste")
			(net "M_G_ECC<6>")
		)
		(pad "55" smd rect
			(at 0 45.900086 270)
			(size 1.8034 0.508)
			(layers "B.Cu" "B.Mask" "B.Paste")
			(net "GND")
		)
		(pad "56" smd rect
			(at 0 46.74997 270)
			(size 1.8034 0.508)
			(layers "B.Cu" "B.Mask" "B.Paste")
			(net "M_G_ECC<2>")
		)
		(pad "57" smd rect
			(at 0 47.600108 270)
			(size 1.8034 0.508)
			(layers "B.Cu" "B.Mask" "B.Paste")
			(net "GND")
		)
		(pad "58" smd rect
			(at 0 48.449992 270)
			(size 1.8034 0.508)
			(layers "B.Cu" "B.Mask" "B.Paste")
			(net "M_GHJ_RST_N")
		)
		(pad "59" smd rect
			(at 0 49.299876 270)
			(size 1.8034 0.508)
			(layers "B.Cu" "B.Mask" "B.Paste")
			(net "PVDDQ_GHJ")
		)
		(pad "60" smd rect
			(at 0 50.150014 270)
			(size 1.8034 0.508)
			(layers "B.Cu" "B.Mask" "B.Paste")
			(net "M_G_CKE<2>")
		)
		(pad "61" smd rect
			(at 0 50.999898 270)
			(size 1.8034 0.508)
			(layers "B.Cu" "B.Mask" "B.Paste")
			(net "PVDDQ_GHJ")
		)
		(pad "62" smd rect
			(at 0 51.850036 270)
			(size 1.8034 0.508)
			(layers "B.Cu" "B.Mask" "B.Paste")
			(net "M_G_ACT_N")
		)
		(pad "63" smd rect
			(at 0 52.69992 270)
			(size 1.8034 0.508)
			(layers "B.Cu" "B.Mask" "B.Paste")
			(net "M_G_BG<0>")
		)
		(pad "64" smd rect
			(at 0 53.550058 270)
			(size 1.8034 0.508)
			(layers "B.Cu" "B.Mask" "B.Paste")
			(net "PVDDQ_GHJ")
		)
		(pad "65" smd rect
			(at 0 54.399942 270)
			(size 1.8034 0.508)
			(layers "B.Cu" "B.Mask" "B.Paste")
			(net "M_G_MA<12>")
		)
		(pad "66" smd rect
			(at 0 55.25008 270)
			(size 1.8034 0.508)
			(layers "B.Cu" "B.Mask" "B.Paste")
			(net "M_G_MA<9>")
		)
		(pad "67" smd rect
			(at 0 56.099964 270)
			(size 1.8034 0.508)
			(layers "B.Cu" "B.Mask" "B.Paste")
			(net "PVDDQ_GHJ")
		)
		(pad "68" smd rect
			(at 0 56.950102 270)
			(size 1.8034 0.508)
			(layers "B.Cu" "B.Mask" "B.Paste")
			(net "M_G_MA<8>")
		)
		(pad "69" smd rect
			(at 0 57.799986 270)
			(size 1.8034 0.508)
			(layers "B.Cu" "B.Mask" "B.Paste")
			(net "M_G_MA<6>")
		)
		(pad "70" smd rect
			(at 0 58.650124 270)
			(size 1.8034 0.508)
			(layers "B.Cu" "B.Mask" "B.Paste")
			(net "PVDDQ_GHJ")
		)
		(pad "71" smd rect
			(at 0 59.500008 270)
			(size 1.8034 0.508)
			(layers "B.Cu" "B.Mask" "B.Paste")
			(net "M_G_MA<3>")
		)
		(pad "72" smd rect
			(at 0 60.349892 270)
			(size 1.8034 0.508)
			(layers "B.Cu" "B.Mask" "B.Paste")
			(net "M_G_MA<1>")
		)
		(pad "73" smd rect
			(at 0 61.20003 270)
			(size 1.8034 0.508)
			(layers "B.Cu" "B.Mask" "B.Paste")
			(net "PVDDQ_GHJ")
		)
		(pad "74" smd rect
			(at 0 62.049914 270)
			(size 1.8034 0.508)
			(layers "B.Cu" "B.Mask" "B.Paste")
			(net "M_G_CLK_DP<2>")
		)
		(pad "75" smd rect
			(at 0 62.900052 270)
			(size 1.8034 0.508)
			(layers "B.Cu" "B.Mask" "B.Paste")
			(net "M_G_CLK_DN<2>")
		)
		(pad "76" smd rect
			(at 0 63.749936 270)
			(size 1.8034 0.508)
			(layers "B.Cu" "B.Mask" "B.Paste")
			(net "PVDDQ_GHJ")
		)
		(pad "77" smd rect
			(at 0 64.600074 270)
			(size 1.8034 0.508)
			(layers "B.Cu" "B.Mask" "B.Paste")
			(net "PVTT_GHJ")
		)
		(pad "78" smd rect
			(at 0 70.550024 270)
			(size 1.8034 0.508)
			(layers "B.Cu" "B.Mask" "B.Paste")
			(net "FM_DIMM_EVENT_COD_N")
		)
		(pad "79" smd rect
			(at 0 71.399908 270)
			(size 1.8034 0.508)
			(layers "B.Cu" "B.Mask" "B.Paste")
			(net "M_G_MA<0>")
		)
		(pad "80" smd rect
			(at 0 72.250046 270)
			(size 1.8034 0.508)
			(layers "B.Cu" "B.Mask" "B.Paste")
			(net "PVDDQ_GHJ")
		)
		(pad "81" smd rect
			(at 0 73.09993 270)
			(size 1.8034 0.508)
			(layers "B.Cu" "B.Mask" "B.Paste")
			(net "M_G_BA<0>")
		)
		(pad "82" smd rect
			(at 0 73.950068 270)
			(size 1.8034 0.508)
			(layers "B.Cu" "B.Mask" "B.Paste")
			(net "M_G_MA<16>")
		)
		(pad "83" smd rect
			(at 0 74.799952 270)
			(size 1.8034 0.508)
			(layers "B.Cu" "B.Mask" "B.Paste")
			(net "PVDDQ_GHJ")
		)
		(pad "84" smd rect
			(at 0 75.65009 270)
			(size 1.8034 0.508)
			(layers "B.Cu" "B.Mask" "B.Paste")
			(net "M_G_CS_N<4>")
		)
		(pad "85" smd rect
			(at 0 76.499974 270)
			(size 1.8034 0.508)
			(layers "B.Cu" "B.Mask" "B.Paste")
			(net "PVDDQ_GHJ")
		)
		(pad "86" smd rect
			(at 0 77.350112 270)
			(size 1.8034 0.508)
			(layers "B.Cu" "B.Mask" "B.Paste")
			(net "M_G_MA<15>")
		)
		(pad "87" smd rect
			(at 0 78.199996 270)
			(size 1.8034 0.508)
			(layers "B.Cu" "B.Mask" "B.Paste")
			(net "M_G_ODT<2>")
		)
		(pad "88" smd rect
			(at 0 79.04988 270)
			(size 1.8034 0.508)
			(layers "B.Cu" "B.Mask" "B.Paste")
			(net "PVDDQ_GHJ")
		)
		(pad "89" smd rect
			(at 0 79.900018 270)
			(size 1.8034 0.508)
			(layers "B.Cu" "B.Mask" "B.Paste")
			(net "M_G_CS_N<5>")
		)
		(pad "90" smd rect
			(at 0 80.749902 270)
			(size 1.8034 0.508)
			(layers "B.Cu" "B.Mask" "B.Paste")
			(net "PVDDQ_GHJ")
		)
		(pad "91" smd rect
			(at 0 81.60004 270)
			(size 1.8034 0.508)
			(layers "B.Cu" "B.Mask" "B.Paste")
			(net "M_G_ODT<3>")
		)
		(pad "92" smd rect
			(at 0 82.449924 270)
			(size 1.8034 0.508)
			(layers "B.Cu" "B.Mask" "B.Paste")
			(net "PVDDQ_GHJ")
		)
		(pad "93" smd rect
			(at 0 83.300062 270)
			(size 1.8034 0.508)
			(layers "B.Cu" "B.Mask" "B.Paste")
			(net "M_G_CS_N<6>")
		)
		(pad "94" smd rect
			(at 0 84.149946 270)
			(size 1.8034 0.508)
			(layers "B.Cu" "B.Mask" "B.Paste")
			(net "GND")
		)
		(pad "95" smd rect
			(at 0 85.000084 270)
			(size 1.8034 0.508)
			(layers "B.Cu" "B.Mask" "B.Paste")
			(net "M_G_DQ<36>")
		)
		(pad "96" smd rect
			(at 0 85.849968 270)
			(size 1.8034 0.508)
			(layers "B.Cu" "B.Mask" "B.Paste")
			(net "GND")
		)
		(pad "97" smd rect
			(at 0 86.700106 270)
			(size 1.8034 0.508)
			(layers "B.Cu" "B.Mask" "B.Paste")
			(net "M_G_DQ<32>")
		)
	)
)
